FILE_TYPE = CONNECTIVITY;
{Allegro Design Entry HDL 17.2-2016 S081 (4005846) 1/11/2022}
"PAGE_NUMBER" = 31;
0"NC";
1"GND\g";
2"GND\g";
3"GND\g";
4"GND\g";
5"GND\g";
6"GND\g";
7"GND\g";
8"GND\g";
9"GND\g";
10"GND\g";
11"GND\g";
12"GND\g";
%"GENOA_SP5"
"28","(-8600,3400)","0","pure_quanta","I19";
;
LOCATION"U25"
$SEC"28"
CDS_SEC"28"
PART_TYPE"SMLF"
MATERIAL"IO"
VALUE"SOCKET6096_13568-001"
PART_NUMBER"DGA^6000030"
CDS_LIB"pure_quanta"
CDS_LMAN_SYM_OUTLINE"-400,3050,400,-3050"
NEEDS_NO_SIZE"TRUE";
"VSS_H34"
$PN"H34"2;
"VSS_H31"
$PN"H31"2;
"VSS_H28"
$PN"H28"2;
"VSS_H25"
$PN"H25"2;
"VSS_H22"
$PN"H22"2;
"VSS_H17"
$PN"H17"2;
"VSS_H15"
$PN"H15"2;
"VSS_H10"
$PN"H10"2;
"VSS_H8"
$PN"H8"2;
"VSS_H3"
$PN"H3"2;
"VSS_G75"
$PN"G75"2;
"VSS_G72"
$PN"G72"2;
"VSS_G70"
$PN"G70"2;
"VSS_G68"
$PN"G68"2;
"VSS_G65"
$PN"G65"2;
"VSS_G63"
$PN"G63"2;
"VSS_G61"
$PN"G61"2;
"VSS_G58"
$PN"G58"2;
"VSS_G56"
$PN"G56"2;
"VSS_G54"
$PN"G54"2;
"VSS_G51"
$PN"G51"2;
"VSS_G48"
$PN"G48"2;
"VSS_G45"
$PN"G45"2;
"VSS_G42"
$PN"G42"2;
"VSS_G34"
$PN"G34"2;
"VSS_G31"
$PN"G31"2;
"VSS_G28"
$PN"G28"2;
"VSS_G25"
$PN"G25"2;
"VSS_G22"
$PN"G22"2;
"VSS_G20"
$PN"G20"2;
"VSS_G18"
$PN"G18"2;
"VSS_G15"
$PN"G15"2;
"VSS_G13"
$PN"G13"2;
"VSS_G11"
$PN"G11"2;
"VSS_G8"
$PN"G8"2;
"VSS_G6"
$PN"G6"2;
"VSS_G4"
$PN"G4"2;
"VSS_G1"
$PN"G1"2;
"VSS_F73"
$PN"F73"2;
"VSS_F71"
$PN"F71"2;
"VSS_F68"
$PN"F68"2;
"VSS_F66"
$PN"F66"2;
"VSS_F64"
$PN"F64"2;
"VSS_F61"
$PN"F61"2;
"VSS_F59"
$PN"F59"2;
"VSS_F57"
$PN"F57"2;
"VSS_F53"
$PN"F53"2;
"VSS_F52"
$PN"F52"2;
"VSS_F50"
$PN"F50"2;
"VSS_F49"
$PN"F49"2;
"VSS_F47"
$PN"F47"2;
"VSS_F46"
$PN"F46"2;
"VSS_F44"
$PN"F44"2;
"VSS_F43"
$PN"F43"2;
"VSS_F41"
$PN"F41"2;
"VSS_F40"
$PN"F40"2;
"VSS_F39"
$PN"F39"2;
"VSS_F37"
$PN"F37"2;
"VSS_F36"
$PN"F36"2;
"VSS_F35"
$PN"F35"2;
"VSS_F33"
$PN"F33"2;
"VSS_F32"
$PN"F32"2;
"VSS_F30"
$PN"F30"2;
"VSS_F29"
$PN"F29"2;
"VSS_F27"
$PN"F27"2;
"VSS_F26"
$PN"F26"2;
"VSS_F24"
$PN"F24"2;
"VSS_F23"
$PN"F23"2;
"VSS_F19"
$PN"F19"2;
"VSS_F17"
$PN"F17"2;
"VSS_F15"
$PN"F15"2;
"VSS_F12"
$PN"F12"2;
"VSS_F10"
$PN"F10"2;
"VSS_F8"
$PN"F8"2;
"VSS_F5"
$PN"F5"2;
"VSS_F3"
$PN"F3"2;
"VSS_E75"
$PN"E75"2;
"VSS_E73"
$PN"E73"2;
"VSS_E72"
$PN"E72"2;
"VSS_E70"
$PN"E70"2;
"VSS_E69"
$PN"E69"2;
"VSS_E68"
$PN"E68"2;
"VSS_E66"
$PN"E66"2;
"VSS_E65"
$PN"E65"2;
"VSS_E63"
$PN"E63"2;
"VSS_E62"
$PN"E62"2;
"VSS_E61"
$PN"E61"2;
"VSS_E59"
$PN"E59"2;
"VSS_E58"
$PN"E58"2;
"VSS_E56"
$PN"E56"2;
"VSS_E55"
$PN"E55"2;
"VSS_E53"
$PN"E53"2;
"VSS_E52"
$PN"E52"2;
"VSS_E21"
$PN"E21"2;
"VSS_E20"
$PN"E20"2;
"VSS_E18"
$PN"E18"2;
"VSS_E17"
$PN"E17"2;
"VSS_E15"
$PN"E15"2;
"VSS_E14"
$PN"E14"2;
"VSS_E13"
$PN"E13"2;
"VSS_E10"
$PN"E10"2;
"VSS_E8"
$PN"E8"1;
"VSS_E7"
$PN"E7"1;
"VSS_E6"
$PN"E6"1;
"VSS_E3"
$PN"E3"1;
"VSS_E1"
$PN"E1"1;
"VSS_D74"
$PN"D74"1;
"VSS_D73"
$PN"D73"1;
"VSS_D71"
$PN"D71"1;
"VSS_D70"
$PN"D70"1;
"VSS_D67"
$PN"D67"1;
"VSS_D66"
$PN"D66"1;
"VSS_D64"
$PN"D64"1;
"VSS_D63"
$PN"D63"1;
"VSS_D61"
$PN"D61"1;
"VSS_D60"
$PN"D60"1;
"VSS_D59"
$PN"D59"1;
"VSS_D57"
$PN"D57"1;
"VSS_D54"
$PN"D54"1;
"VSS_D53"
$PN"D53"1;
"VSS_D52"
$PN"D52"1;
"VSS_D51"
$PN"D51"1;
"VSS_D50"
$PN"D50"1;
"VSS_D49"
$PN"D49"1;
"VSS_D48"
$PN"D48"1;
"VSS_D47"
$PN"D47"1;
"VSS_D46"
$PN"D46"1;
"VSS_D45"
$PN"D45"1;
"VSS_D44"
$PN"D44"1;
"VSS_D43"
$PN"D43"1;
"VSS_D42"
$PN"D42"1;
"VSS_D41"
$PN"D41"1;
"VSS_D40"
$PN"D40"1;
"VSS_D39"
$PN"D39"1;
"VSS_D37"
$PN"D37"1;
"VSS_D35"
$PN"D35"1;
"VSS_D31"
$PN"D31"1;
"VSS_D30"
$PN"D30"1;
"VSS_D29"
$PN"D29"1;
"VSS_D28"
$PN"D28"1;
"VSS_D27"
$PN"D27"1;
"VSS_D26"
$PN"D26"1;
"VSS_D25"
$PN"D25"1;
"VSS_D24"
$PN"D24"1;
"VSS_D21"
$PN"D21"1;
"VSS_D20"
$PN"D20"1;
"VSS_D19"
$PN"D19"1;
"VSS_D17"
$PN"D17"1;
"VSS_D16"
$PN"D16"1;
"VSS_D13"
$PN"D13"1;
"VSS_D12"
$PN"D12"1;
"VSS_D10"
$PN"D10"1;
"VSS_D9"
$PN"D9"1;
"VSS_D6"
$PN"D6"1;
"VSS_D5"
$PN"D5"1;
"VSS_D3"
$PN"D3"1;
"VSS_D2"
$PN"D2"1;
"VSS_C75"
$PN"C75"1;
"VSS_C73"
$PN"C73"1;
"VSS_C71"
$PN"C71"1;
"VSS_C69"
$PN"C69"1;
"VSS_C67"
$PN"C67"1;
"VSS_C64"
$PN"C64"1;
"VSS_C61"
$PN"C61"1;
"VSS_C57"
$PN"C57"1;
"VSS_C56"
$PN"C56"1;
"VSS_C55"
$PN"C55"1;
"VSS_C52"
$PN"C52"1;
"VSS_C49"
$PN"C49"1;
"VSS_C46"
$PN"C46"1;
"VSS_C43"
$PN"C43"1;
"VSS_C40"
$PN"C40"1;
"VSS_C36"
$PN"C36"1;
"VSS_C30"
$PN"C30"1;
"VSS_C27"
$PN"C27"1;
"VSS_C24"
$PN"C24"1;
"VSS_C21"
$PN"C21"1;
"VSS_C15"
$PN"C15"1;
"VSS_C13"
$PN"C13"1;
"VSS_C11"
$PN"C11"1;
"VSS_C10"
$PN"C10"1;
"VSS_C8"
$PN"C8"1;
"VSS_C5"
$PN"C5"1;
"VSS_C1"
$PN"C1"1;
"VSS_B70"
$PN"B70"1;
"VSS_B68"
$PN"B68"1;
"VSS_B65"
$PN"B65"1;
"VSS_B62"
$PN"B62"1;
"VSS_B59"
$PN"B59"1;
"VSS_B55"
$PN"B55"1;
"VSS_B52"
$PN"B52"1;
"VSS_B49"
$PN"B49"1;
"VSS_B46"
$PN"B46"1;
"VSS_B43"
$PN"B43"1;
"VSS_B39"
$PN"B39"1;
"VSS_B37"
$PN"B37"1;
"VSS_B33"
$PN"B33"1;
"VSS_B30"
$PN"B30"1;
"VSS_B27"
$PN"B27"1;
"VSS_B24"
$PN"B24"1;
"VSS_B18"
$PN"B18"1;
"VSS_B13"
$PN"B13"1;
"VSS_B11"
$PN"B11"1;
"VSS_B10"
$PN"B10"1;
"VSS_B8"
$PN"B8"1;
"VSS_B7"
$PN"B7"1;
"VSS_A73"
$PN"A73"1;
"VSS_A72"
$PN"A72"1;
"VSS_A67"
$PN"A67"1;
"VSS_A61"
$PN"A61"1;
"VSS_A53"
$PN"A53"1;
"VSS_A49"
$PN"A49"1;
"VSS_A47"
$PN"A47"1;
"VSS_A44"
$PN"A44"1;
"VSS_A43"
$PN"A43"1;
"VSS_A27"
$PN"A27"1;
"VSS_A21"
$PN"A21"1;
"VSS_A15"
$PN"A15"1;
"VSS_A9"
$PN"A9"1;
"VSS_A3"
$PN"A3"1;
"VSS_J13"
$PN"J13"2;
"VSS_J11"
$PN"J11"2;
"VSS_J8"
$PN"J8"2;
"VSS_J6"
$PN"J6"2;
"VSS_J4"
$PN"J4"2;
"VSS_J1"
$PN"J1"2;
"VSS_H73"
$PN"H73"2;
"VSS_H68"
$PN"H68"2;
"VSS_H66"
$PN"H66"2;
"VSS_H61"
$PN"H61"2;
"VSS_H59"
$PN"H59"2;
"VSS_H54"
$PN"H54"2;
"VSS_H51"
$PN"H51"2;
"VSS_H48"
$PN"H48"2;
"VSS_H45"
$PN"H45"2;
"VSS_H42"
$PN"H42"2;
"VSS_H39"
$PN"H39"2;
"VSS_H37"
$PN"H37"2;
%"GENOA_SP5"
"29","(-7075,3425)","0","pure_quanta","I20";
;
LOCATION"U25"
$SEC"29"
CDS_SEC"29"
PART_TYPE"SMLF"
MATERIAL"IO"
VALUE"SOCKET6096_13568-001"
PART_NUMBER"DGA^6000030"
NEEDS_NO_SIZE"TRUE"
CDS_LMAN_SYM_OUTLINE"-400,3050,400,-3050"
CDS_LIB"pure_quanta";
"VSS_R45"
$PN"R45"4;
"VSS_R42"
$PN"R42"4;
"VSS_R41"
$PN"R41"4;
"VSS_R40"
$PN"R40"4;
"VSS_R36"
$PN"R36"4;
"VSS_R35"
$PN"R35"4;
"VSS_R34"
$PN"R34"4;
"VSS_R31"
$PN"R31"4;
"VSS_R28"
$PN"R28"4;
"VSS_R25"
$PN"R25"4;
"VSS_R22"
$PN"R22"4;
"VSS_R20"
$PN"R20"4;
"VSS_R18"
$PN"R18"4;
"VSS_R15"
$PN"R15"4;
"VSS_R13"
$PN"R13"4;
"VSS_R11"
$PN"R11"4;
"VSS_R8"
$PN"R8"4;
"VSS_R6"
$PN"R6"4;
"VSS_R4"
$PN"R4"4;
"VSS_R1"
$PN"R1"4;
"VSS_P73"
$PN"P73"4;
"VSS_P66"
$PN"P66"4;
"VSS_P61"
$PN"P61"4;
"VSS_P59"
$PN"P59"4;
"VSS_P53"
$PN"P53"4;
"VSS_P52"
$PN"P52"4;
"VSS_P51"
$PN"P51"4;
"VSS_P50"
$PN"P50"4;
"VSS_P49"
$PN"P49"4;
"VSS_P48"
$PN"P48"4;
"VSS_P47"
$PN"P47"4;
"VSS_P46"
$PN"P46"4;
"VSS_P45"
$PN"P45"4;
"VSS_P44"
$PN"P44"4;
"VSS_P43"
$PN"P43"4;
"VSS_P42"
$PN"P42"4;
"VSS_P39"
$PN"P39"4;
"VSS_P37"
$PN"P37"4;
"VSS_P34"
$PN"P34"4;
"VSS_P33"
$PN"P33"4;
"VSS_P32"
$PN"P32"4;
"VSS_P31"
$PN"P31"4;
"VSS_P30"
$PN"P30"4;
"VSS_P29"
$PN"P29"4;
"VSS_P28"
$PN"P28"4;
"VSS_P27"
$PN"P27"4;
"VSS_P26"
$PN"P26"4;
"VSS_P24"
$PN"P24"4;
"VSS_P23"
$PN"P23"4;
"VSS_P17"
$PN"P17"4;
"VSS_P15"
$PN"P15"4;
"VSS_P10"
$PN"P10"4;
"VSS_P8"
$PN"P8"4;
"VSS_P3"
$PN"P3"4;
"VSS_N75"
$PN"N75"4;
"VSS_N72"
$PN"N72"4;
"VSS_N70"
$PN"N70"4;
"VSS_N68"
$PN"N68"4;
"VSS_N65"
$PN"N65"4;
"VSS_N63"
$PN"N63"4;
"VSS_N61"
$PN"N61"4;
"VSS_N58"
$PN"N58"4;
"VSS_N56"
$PN"N56"4;
"VSS_N54"
$PN"N54"4;
"VSS_N51"
$PN"N51"4;
"VSS_N48"
$PN"N48"4;
"VSS_N45"
$PN"N45"4;
"VSS_N42"
$PN"N42"4;
"VSS_N34"
$PN"N34"4;
"VSS_N31"
$PN"N31"4;
"VSS_N28"
$PN"N28"4;
"VSS_N25"
$PN"N25"4;
"VSS_N22"
$PN"N22"4;
"VSS_N20"
$PN"N20"4;
"VSS_N18"
$PN"N18"4;
"VSS_N15"
$PN"N15"4;
"VSS_N13"
$PN"N13"4;
"VSS_N11"
$PN"N11"4;
"VSS_N8"
$PN"N8"4;
"VSS_N6"
$PN"N6"4;
"VSS_N4"
$PN"N4"4;
"VSS_N1"
$PN"N1"3;
"VSS_M73"
$PN"M73"3;
"VSS_M71"
$PN"M71"3;
"VSS_M68"
$PN"M68"3;
"VSS_M66"
$PN"M66"3;
"VSS_M64"
$PN"M64"3;
"VSS_M61"
$PN"M61"3;
"VSS_M59"
$PN"M59"3;
"VSS_M57"
$PN"M57"3;
"VSS_M54"
$PN"M54"3;
"VSS_M51"
$PN"M51"3;
"VSS_M48"
$PN"M48"3;
"VSS_M45"
$PN"M45"3;
"VSS_M42"
$PN"M42"3;
"VSS_M39"
$PN"M39"3;
"VSS_M37"
$PN"M37"3;
"VSS_M34"
$PN"M34"3;
"VSS_M31"
$PN"M31"3;
"VSS_M28"
$PN"M28"3;
"VSS_M25"
$PN"M25"3;
"VSS_M22"
$PN"M22"3;
"VSS_M19"
$PN"M19"3;
"VSS_M17"
$PN"M17"3;
"VSS_M15"
$PN"M15"3;
"VSS_M12"
$PN"M12"3;
"VSS_M10"
$PN"M10"3;
"VSS_M8"
$PN"M8"3;
"VSS_M5"
$PN"M5"3;
"VSS_M3"
$PN"M3"3;
"VSS_L75"
$PN"L75"3;
"VSS_L70"
$PN"L70"3;
"VSS_L68"
$PN"L68"3;
"VSS_L63"
$PN"L63"3;
"VSS_L61"
$PN"L61"3;
"VSS_L56"
$PN"L56"3;
"VSS_L54"
$PN"L54"3;
"VSS_L51"
$PN"L51"3;
"VSS_L48"
$PN"L48"3;
"VSS_L45"
$PN"L45"3;
"VSS_L42"
$PN"L42"3;
"VSS_L41"
$PN"L41"3;
"VSS_L40"
$PN"L40"3;
"VSS_L36"
$PN"L36"3;
"VSS_L35"
$PN"L35"3;
"VSS_L34"
$PN"L34"3;
"VSS_L31"
$PN"L31"3;
"VSS_L28"
$PN"L28"3;
"VSS_L25"
$PN"L25"3;
"VSS_L22"
$PN"L22"3;
"VSS_L20"
$PN"L20"3;
"VSS_L15"
$PN"L15"3;
"VSS_L13"
$PN"L13"3;
"VSS_L8"
$PN"L8"3;
"VSS_L6"
$PN"L6"3;
"VSS_L1"
$PN"L1"3;
"VSS_K73"
$PN"K73"3;
"VSS_K71"
$PN"K71"3;
"VSS_K68"
$PN"K68"3;
"VSS_K66"
$PN"K66"3;
"VSS_K64"
$PN"K64"3;
"VSS_K61"
$PN"K61"3;
"VSS_K57"
$PN"K57"3;
"VSS_K53"
$PN"K53"3;
"VSS_K52"
$PN"K52"3;
"VSS_K51"
$PN"K51"3;
"VSS_K50"
$PN"K50"3;
"VSS_K49"
$PN"K49"3;
"VSS_K48"
$PN"K48"3;
"VSS_K47"
$PN"K47"3;
"VSS_K46"
$PN"K46"3;
"VSS_K45"
$PN"K45"3;
"VSS_K44"
$PN"K44"3;
"VSS_K43"
$PN"K43"3;
"VSS_K42"
$PN"K42"3;
"VSS_K39"
$PN"K39"3;
"VSS_K37"
$PN"K37"3;
"VSS_K34"
$PN"K34"3;
"VSS_K33"
$PN"K33"3;
"VSS_K32"
$PN"K32"3;
"VSS_K31"
$PN"K31"3;
"VSS_K30"
$PN"K30"3;
"VSS_K29"
$PN"K29"3;
"VSS_K28"
$PN"K28"3;
"VSS_K27"
$PN"K27"3;
"VSS_K26"
$PN"K26"3;
"VSS_K25"
$PN"K25"3;
"VSS_K24"
$PN"K24"3;
"VSS_K19"
$PN"K19"3;
"VSS_K17"
$PN"K17"3;
"VSS_K15"
$PN"K15"3;
"VSS_K12"
$PN"K12"3;
"VSS_K10"
$PN"K10"3;
"VSS_K8"
$PN"K8"3;
"VSS_K5"
$PN"K5"3;
"VSS_K3"
$PN"K3"3;
"VSS_J75"
$PN"J75"3;
"VSS_J72"
$PN"J72"3;
"VSS_J70"
$PN"J70"3;
"VSS_J68"
$PN"J68"3;
"VSS_J65"
$PN"J65"3;
"VSS_J63"
$PN"J63"3;
"VSS_J61"
$PN"J61"3;
"VSS_J58"
$PN"J58"3;
"VSS_J56"
$PN"J56"3;
"VSS_J54"
$PN"J54"3;
"VSS_J51"
$PN"J51"3;
"VSS_J48"
$PN"J48"3;
"VSS_J45"
$PN"J45"3;
"VSS_J42"
$PN"J42"3;
"VSS_J34"
$PN"J34"3;
"VSS_J31"
$PN"J31"3;
"VSS_J28"
$PN"J28"3;
"VSS_J25"
$PN"J25"3;
"VSS_J22"
$PN"J22"3;
"VSS_J20"
$PN"J20"3;
"VSS_J18"
$PN"J18"3;
"VSS_J15"
$PN"J15"3;
"VSS_T64"
$PN"T64"4;
"VSS_T61"
$PN"T61"4;
"VSS_T59"
$PN"T59"4;
"VSS_T57"
$PN"T57"4;
"VSS_T54"
$PN"T54"4;
"VSS_T51"
$PN"T51"4;
"VSS_T48"
$PN"T48"4;
"VSS_T45"
$PN"T45"4;
"VSS_T42"
$PN"T42"4;
"VSS_T39"
$PN"T39"4;
"VSS_T37"
$PN"T37"4;
"VSS_T34"
$PN"T34"4;
"VSS_T31"
$PN"T31"4;
"VSS_T28"
$PN"T28"4;
"VSS_T25"
$PN"T25"4;
"VSS_T22"
$PN"T22"4;
"VSS_T19"
$PN"T19"4;
"VSS_T17"
$PN"T17"4;
"VSS_T15"
$PN"T15"4;
"VSS_T12"
$PN"T12"4;
"VSS_T10"
$PN"T10"4;
"VSS_T8"
$PN"T8"4;
"VSS_T5"
$PN"T5"4;
"VSS_T3"
$PN"T3"4;
"VSS_R75"
$PN"R75"4;
"VSS_R72"
$PN"R72"4;
"VSS_R70"
$PN"R70"4;
"VSS_R68"
$PN"R68"4;
"VSS_R65"
$PN"R65"4;
"VSS_R63"
$PN"R63"4;
"VSS_R61"
$PN"R61"4;
"VSS_R58"
$PN"R58"4;
"VSS_R56"
$PN"R56"4;
"VSS_R54"
$PN"R54"4;
"VSS_R51"
$PN"R51"4;
"VSS_R48"
$PN"R48"4;
%"GENOA_SP5"
"30","(-5600,3450)","0","pure_quanta","I21";
;
LOCATION"U25"
$SEC"30"
CDS_SEC"30"
PART_TYPE"SMLF"
MATERIAL"IO"
VALUE"SOCKET6096_13568-001"
PART_NUMBER"DGA^6000030"
NEEDS_NO_SIZE"TRUE"
CDS_LMAN_SYM_OUTLINE"-400,3050,400,-3050"
CDS_LIB"pure_quanta";
"VSS_AB66"
$PN"AB66"6;
"VSS_AB64"
$PN"AB64"6;
"VSS_AB61"
$PN"AB61"6;
"VSS_AB59"
$PN"AB59"6;
"VSS_AB57"
$PN"AB57"6;
"VSS_AB54"
$PN"AB54"6;
"VSS_AB51"
$PN"AB51"6;
"VSS_AB48"
$PN"AB48"6;
"VSS_AB45"
$PN"AB45"6;
"VSS_AB42"
$PN"AB42"6;
"VSS_AB39"
$PN"AB39"6;
"VSS_AB37"
$PN"AB37"6;
"VSS_AB34"
$PN"AB34"6;
"VSS_AB31"
$PN"AB31"6;
"VSS_AB28"
$PN"AB28"6;
"VSS_AB25"
$PN"AB25"6;
"VSS_AB22"
$PN"AB22"6;
"VSS_AB19"
$PN"AB19"6;
"VSS_AB17"
$PN"AB17"6;
"VSS_AB15"
$PN"AB15"6;
"VSS_AB12"
$PN"AB12"6;
"VSS_AB10"
$PN"AB10"6;
"VSS_AB8"
$PN"AB8"6;
"VSS_AB5"
$PN"AB5"6;
"VSS_AB3"
$PN"AB3"6;
"VSS_AA75"
$PN"AA75"6;
"VSS_AA70"
$PN"AA70"6;
"VSS_AA68"
$PN"AA68"6;
"VSS_AA65"
$PN"AA65"6;
"VSS_AA63"
$PN"AA63"6;
"VSS_AA61"
$PN"AA61"6;
"VSS_AA58"
$PN"AA58"6;
"VSS_AA56"
$PN"AA56"6;
"VSS_AA45"
$PN"AA45"6;
"VSS_AA41"
$PN"AA41"6;
"VSS_AA40"
$PN"AA40"6;
"VSS_AA36"
$PN"AA36"6;
"VSS_AA35"
$PN"AA35"6;
"VSS_AA34"
$PN"AA34"6;
"VSS_AA31"
$PN"AA31"6;
"VSS_AA20"
$PN"AA20"6;
"VSS_AA18"
$PN"AA18"6;
"VSS_AA15"
$PN"AA15"6;
"VSS_AA13"
$PN"AA13"6;
"VSS_AA11"
$PN"AA11"6;
"VSS_AA8"
$PN"AA8"6;
"VSS_AA6"
$PN"AA6"6;
"VSS_AA4"
$PN"AA4"6;
"VSS_AA1"
$PN"AA1"6;
"VSS_Y73"
$PN"Y73"6;
"VSS_Y68"
$PN"Y68"6;
"VSS_Y66"
$PN"Y66"6;
"VSS_Y61"
$PN"Y61"6;
"VSS_Y59"
$PN"Y59"6;
"VSS_Y54"
$PN"Y54"6;
"VSS_Y53"
$PN"Y53"6;
"VSS_Y52"
$PN"Y52"6;
"VSS_Y51"
$PN"Y51"6;
"VSS_Y50"
$PN"Y50"6;
"VSS_Y49"
$PN"Y49"6;
"VSS_Y48"
$PN"Y48"6;
"VSS_Y45"
$PN"Y45"6;
"VSS_Y44"
$PN"Y44"6;
"VSS_Y43"
$PN"Y43"5;
"VSS_Y42"
$PN"Y42"5;
"VSS_Y39"
$PN"Y39"5;
"VSS_Y37"
$PN"Y37"5;
"VSS_Y34"
$PN"Y34"5;
"VSS_Y33"
$PN"Y33"5;
"VSS_Y32"
$PN"Y32"5;
"VSS_Y31"
$PN"Y31"5;
"VSS_Y28"
$PN"Y28"5;
"VSS_Y27"
$PN"Y27"5;
"VSS_Y26"
$PN"Y26"5;
"VSS_Y25"
$PN"Y25"5;
"VSS_Y24"
$PN"Y24"5;
"VSS_Y23"
$PN"Y23"5;
"VSS_Y22"
$PN"Y22"5;
"VSS_Y17"
$PN"Y17"5;
"VSS_Y15"
$PN"Y15"5;
"VSS_Y10"
$PN"Y10"5;
"VSS_Y8"
$PN"Y8"5;
"VSS_Y3"
$PN"Y3"5;
"VSS_W75"
$PN"W75"5;
"VSS_W72"
$PN"W72"5;
"VSS_W70"
$PN"W70"5;
"VSS_W68"
$PN"W68"5;
"VSS_W65"
$PN"W65"5;
"VSS_W63"
$PN"W63"5;
"VSS_W61"
$PN"W61"5;
"VSS_W58"
$PN"W58"5;
"VSS_W56"
$PN"W56"5;
"VSS_W54"
$PN"W54"5;
"VSS_W51"
$PN"W51"5;
"VSS_W48"
$PN"W48"5;
"VSS_W45"
$PN"W45"5;
"VSS_W42"
$PN"W42"5;
"VSS_W41"
$PN"W41"5;
"VSS_W40"
$PN"W40"5;
"VSS_W36"
$PN"W36"5;
"VSS_W35"
$PN"W35"5;
"VSS_W34"
$PN"W34"5;
"VSS_W28"
$PN"W28"5;
"VSS_W25"
$PN"W25"5;
"VSS_W22"
$PN"W22"5;
"VSS_W20"
$PN"W20"5;
"VSS_W18"
$PN"W18"5;
"VSS_W15"
$PN"W15"5;
"VSS_W13"
$PN"W13"5;
"VSS_W11"
$PN"W11"5;
"VSS_W8"
$PN"W8"5;
"VSS_W6"
$PN"W6"5;
"VSS_W4"
$PN"W4"5;
"VSS_W1"
$PN"W1"5;
"VSS_V73"
$PN"V73"5;
"VSS_V71"
$PN"V71"5;
"VSS_V66"
$PN"V66"5;
"VSS_V64"
$PN"V64"5;
"VSS_V61"
$PN"V61"5;
"VSS_V59"
$PN"V59"5;
"VSS_V57"
$PN"V57"5;
"VSS_V53"
$PN"V53"5;
"VSS_V52"
$PN"V52"5;
"VSS_V51"
$PN"V51"5;
"VSS_V50"
$PN"V50"5;
"VSS_V49"
$PN"V49"5;
"VSS_V48"
$PN"V48"5;
"VSS_V47"
$PN"V47"5;
"VSS_V46"
$PN"V46"5;
"VSS_V45"
$PN"V45"5;
"VSS_V44"
$PN"V44"5;
"VSS_V43"
$PN"V43"5;
"VSS_V42"
$PN"V42"5;
"VSS_V39"
$PN"V39"5;
"VSS_V37"
$PN"V37"5;
"VSS_V34"
$PN"V34"5;
"VSS_V33"
$PN"V33"5;
"VSS_V32"
$PN"V32"5;
"VSS_V31"
$PN"V31"5;
"VSS_V30"
$PN"V30"5;
"VSS_V29"
$PN"V29"5;
"VSS_V28"
$PN"V28"5;
"VSS_V26"
$PN"V26"5;
"VSS_V25"
$PN"V25"5;
"VSS_V24"
$PN"V24"5;
"VSS_V23"
$PN"V23"5;
"VSS_V19"
$PN"V19"5;
"VSS_V17"
$PN"V17"5;
"VSS_V15"
$PN"V15"5;
"VSS_V12"
$PN"V12"5;
"VSS_V10"
$PN"V10"5;
"VSS_V8"
$PN"V8"5;
"VSS_V5"
$PN"V5"5;
"VSS_V3"
$PN"V3"5;
"VSS_U75"
$PN"U75"5;
"VSS_U70"
$PN"U70"5;
"VSS_U68"
$PN"U68"5;
"VSS_U63"
$PN"U63"5;
"VSS_U61"
$PN"U61"5;
"VSS_U56"
$PN"U56"5;
"VSS_U54"
$PN"U54"5;
"VSS_U51"
$PN"U51"5;
"VSS_U48"
$PN"U48"5;
"VSS_U45"
$PN"U45"5;
"VSS_U42"
$PN"U42"5;
"VSS_U34"
$PN"U34"5;
"VSS_U31"
$PN"U31"5;
"VSS_U28"
$PN"U28"5;
"VSS_U25"
$PN"U25"5;
"VSS_U22"
$PN"U22"5;
"VSS_U20"
$PN"U20"5;
"VSS_U15"
$PN"U15"5;
"VSS_U13"
$PN"U13"5;
"VSS_U8"
$PN"U8"5;
"VSS_U6"
$PN"U6"5;
"VSS_U1"
$PN"U1"5;
"VSS_T73"
$PN"T73"5;
"VSS_T71"
$PN"T71"5;
"VSS_T68"
$PN"T68"5;
"VSS_T66"
$PN"T66"5;
"VSS_AD48"
$PN"AD48"6;
"VSS_AD47"
$PN"AD47"6;
"VSS_AD46"
$PN"AD46"6;
"VSS_AD45"
$PN"AD45"6;
"VSS_AD44"
$PN"AD44"6;
"VSS_AD43"
$PN"AD43"6;
"VSS_AD42"
$PN"AD42"6;
"VSS_AD39"
$PN"AD39"6;
"VSS_AD37"
$PN"AD37"6;
"VSS_AD34"
$PN"AD34"6;
"VSS_AD33"
$PN"AD33"6;
"VSS_AD32"
$PN"AD32"6;
"VSS_AD30"
$PN"AD30"6;
"VSS_AD29"
$PN"AD29"6;
"VSS_AD28"
$PN"AD28"6;
"VSS_AD27"
$PN"AD27"6;
"VSS_AD26"
$PN"AD26"6;
"VSS_AD25"
$PN"AD25"6;
"VSS_AD24"
$PN"AD24"6;
"VSS_AD23"
$PN"AD23"6;
"VSS_AD19"
$PN"AD19"6;
"VSS_AD17"
$PN"AD17"6;
"VSS_AD15"
$PN"AD15"6;
"VSS_AD12"
$PN"AD12"6;
"VSS_AD10"
$PN"AD10"6;
"VSS_AD8"
$PN"AD8"6;
"VSS_AD5"
$PN"AD5"6;
"VSS_AD3"
$PN"AD3"6;
"VSS_AC75"
$PN"AC75"6;
"VSS_AC70"
$PN"AC70"6;
"VSS_AC68"
$PN"AC68"6;
"VSS_AC63"
$PN"AC63"6;
"VSS_AC61"
$PN"AC61"6;
"VSS_AC56"
$PN"AC56"6;
"VSS_AC54"
$PN"AC54"6;
"VSS_AC51"
$PN"AC51"6;
"VSS_AC48"
$PN"AC48"6;
"VSS_AC45"
$PN"AC45"6;
"VSS_AC42"
$PN"AC42"6;
"VSS_AC34"
$PN"AC34"6;
"VSS_AC31"
$PN"AC31"6;
"VSS_AC28"
$PN"AC28"6;
"VSS_AC25"
$PN"AC25"6;
"VSS_AC22"
$PN"AC22"6;
"VSS_AC20"
$PN"AC20"6;
"VSS_AC15"
$PN"AC15"6;
"VSS_AC13"
$PN"AC13"6;
"VSS_AC8"
$PN"AC8"6;
"VSS_AC6"
$PN"AC6"6;
"VSS_AC1"
$PN"AC1"6;
"VSS_AB73"
$PN"AB73"6;
"VSS_AB71"
$PN"AB71"6;
"VSS_AB68"
$PN"AB68"6;
%"GENOA_SP5"
"31","(-4100,3475)","0","pure_quanta","I22";
;
LOCATION"U25"
$SEC"31"
CDS_SEC"31"
PART_TYPE"SMLF"
MATERIAL"IO"
VALUE"SOCKET6096_13568-001"
PART_NUMBER"DGA^6000030"
NEEDS_NO_SIZE"TRUE"
CDS_LMAN_SYM_OUTLINE"-400,3050,400,-3050"
CDS_LIB"pure_quanta";
"VSS_AK8"
$PN"AK8"8;
"VSS_AK5"
$PN"AK5"8;
"VSS_AK3"
$PN"AK3"8;
"VSS_AJ75"
$PN"AJ75"8;
"VSS_AJ70"
$PN"AJ70"8;
"VSS_AJ68"
$PN"AJ68"8;
"VSS_AJ63"
$PN"AJ63"8;
"VSS_AJ61"
$PN"AJ61"8;
"VSS_AJ56"
$PN"AJ56"8;
"VSS_AJ54"
$PN"AJ54"8;
"VSS_AJ51"
$PN"AJ51"8;
"VSS_AJ48"
$PN"AJ48"8;
"VSS_AJ45"
$PN"AJ45"8;
"VSS_AJ42"
$PN"AJ42"8;
"VSS_AJ41"
$PN"AJ41"8;
"VSS_AJ40"
$PN"AJ40"8;
"VSS_AJ36"
$PN"AJ36"8;
"VSS_AJ35"
$PN"AJ35"8;
"VSS_AJ34"
$PN"AJ34"8;
"VSS_AJ31"
$PN"AJ31"8;
"VSS_AJ28"
$PN"AJ28"8;
"VSS_AJ25"
$PN"AJ25"8;
"VSS_AJ22"
$PN"AJ22"8;
"VSS_AJ20"
$PN"AJ20"8;
"VSS_AJ15"
$PN"AJ15"8;
"VSS_AJ8"
$PN"AJ8"8;
"VSS_AJ6"
$PN"AJ6"8;
"VSS_AJ1"
$PN"AJ1"8;
"VSS_AH73"
$PN"AH73"8;
"VSS_AH71"
$PN"AH71"8;
"VSS_AH68"
$PN"AH68"8;
"VSS_AH66"
$PN"AH66"8;
"VSS_AH64"
$PN"AH64"8;
"VSS_AH61"
$PN"AH61"8;
"VSS_AH59"
$PN"AH59"8;
"VSS_AH57"
$PN"AH57"8;
"VSS_AH53"
$PN"AH53"8;
"VSS_AH52"
$PN"AH52"8;
"VSS_AH51"
$PN"AH51"8;
"VSS_AH50"
$PN"AH50"8;
"VSS_AH49"
$PN"AH49"8;
"VSS_AH48"
$PN"AH48"8;
"VSS_AH47"
$PN"AH47"8;
"VSS_AH46"
$PN"AH46"8;
"VSS_AH45"
$PN"AH45"8;
"VSS_AH44"
$PN"AH44"8;
"VSS_AH43"
$PN"AH43"7;
"VSS_AH42"
$PN"AH42"7;
"VSS_AH39"
$PN"AH39"7;
"VSS_AH37"
$PN"AH37"7;
"VSS_AH34"
$PN"AH34"7;
"VSS_AH32"
$PN"AH32"7;
"VSS_AH31"
$PN"AH31"7;
"VSS_AH30"
$PN"AH30"7;
"VSS_AH29"
$PN"AH29"7;
"VSS_AH28"
$PN"AH28"7;
"VSS_AH27"
$PN"AH27"7;
"VSS_AH26"
$PN"AH26"7;
"VSS_AH25"
$PN"AH25"7;
"VSS_AH24"
$PN"AH24"7;
"VSS_AH23"
$PN"AH23"7;
"VSS_AH19"
$PN"AH19"7;
"VSS_AH17"
$PN"AH17"7;
"VSS_AH15"
$PN"AH15"7;
"VSS_AH12"
$PN"AH12"7;
"VSS_AH10"
$PN"AH10"7;
"VSS_AH8"
$PN"AH8"7;
"VSS_AH5"
$PN"AH5"7;
"VSS_AH3"
$PN"AH3"7;
"VSS_AG75"
$PN"AG75"7;
"VSS_AG72"
$PN"AG72"7;
"VSS_AG70"
$PN"AG70"7;
"VSS_AG68"
$PN"AG68"7;
"VSS_AG65"
$PN"AG65"7;
"VSS_AG63"
$PN"AG63"7;
"VSS_AG61"
$PN"AG61"7;
"VSS_AG58"
$PN"AG58"7;
"VSS_AG56"
$PN"AG56"7;
"VSS_AG54"
$PN"AG54"7;
"VSS_AG51"
$PN"AG51"7;
"VSS_AG48"
$PN"AG48"7;
"VSS_AG45"
$PN"AG45"7;
"VSS_AG42"
$PN"AG42"7;
"VSS_AG34"
$PN"AG34"7;
"VSS_AG31"
$PN"AG31"7;
"VSS_AG28"
$PN"AG28"7;
"VSS_AG25"
$PN"AG25"7;
"VSS_AG22"
$PN"AG22"7;
"VSS_AG20"
$PN"AG20"7;
"VSS_AG18"
$PN"AG18"7;
"VSS_AG15"
$PN"AG15"7;
"VSS_AG13"
$PN"AG13"7;
"VSS_AG11"
$PN"AG11"7;
"VSS_AG8"
$PN"AG8"7;
"VSS_AG6"
$PN"AG6"7;
"VSS_AG4"
$PN"AG4"7;
"VSS_AG1"
$PN"AG1"7;
"VSS_AF73"
$PN"AF73"7;
"VSS_AF68"
$PN"AF68"7;
"VSS_AF66"
$PN"AF66"7;
"VSS_AF61"
$PN"AF61"7;
"VSS_AF59"
$PN"AF59"7;
"VSS_AF54"
$PN"AF54"7;
"VSS_AF51"
$PN"AF51"7;
"VSS_AF48"
$PN"AF48"7;
"VSS_AF45"
$PN"AF45"7;
"VSS_AF42"
$PN"AF42"7;
"VSS_AF39"
$PN"AF39"7;
"VSS_AF37"
$PN"AF37"7;
"VSS_AF34"
$PN"AF34"7;
"VSS_AF31"
$PN"AF31"7;
"VSS_AF28"
$PN"AF28"7;
"VSS_AF25"
$PN"AF25"7;
"VSS_AF22"
$PN"AF22"7;
"VSS_AF17"
$PN"AF17"7;
"VSS_AF15"
$PN"AF15"7;
"VSS_AF10"
$PN"AF10"7;
"VSS_AF8"
$PN"AF8"7;
"VSS_AF3"
$PN"AF3"7;
"VSS_AE75"
$PN"AE75"7;
"VSS_AE72"
$PN"AE72"7;
"VSS_AE70"
$PN"AE70"7;
"VSS_AE68"
$PN"AE68"7;
"VSS_AE65"
$PN"AE65"7;
"VSS_AE63"
$PN"AE63"7;
"VSS_AE61"
$PN"AE61"7;
"VSS_AE58"
$PN"AE58"7;
"VSS_AE56"
$PN"AE56"7;
"VSS_AE54"
$PN"AE54"7;
"VSS_AE51"
$PN"AE51"7;
"VSS_AE48"
$PN"AE48"7;
"VSS_AE45"
$PN"AE45"7;
"VSS_AE42"
$PN"AE42"7;
"VSS_AE41"
$PN"AE41"7;
"VSS_AE40"
$PN"AE40"7;
"VSS_AE36"
$PN"AE36"7;
"VSS_AE35"
$PN"AE35"7;
"VSS_AE34"
$PN"AE34"7;
"VSS_AE31"
$PN"AE31"7;
"VSS_AE28"
$PN"AE28"7;
"VSS_AE25"
$PN"AE25"7;
"VSS_AE22"
$PN"AE22"7;
"VSS_AE20"
$PN"AE20"7;
"VSS_AE18"
$PN"AE18"7;
"VSS_AE15"
$PN"AE15"7;
"VSS_AE13"
$PN"AE13"7;
"VSS_AE11"
$PN"AE11"7;
"VSS_AE8"
$PN"AE8"7;
"VSS_AE6"
$PN"AE6"7;
"VSS_AE1"
$PN"AE1"7;
"VSS_AD73"
$PN"AD73"7;
"VSS_AD71"
$PN"AD71"7;
"VSS_AD68"
$PN"AD68"7;
"VSS_AD66"
$PN"AD66"7;
"VSS_AD64"
$PN"AD64"7;
"VSS_AD61"
$PN"AD61"7;
"VSS_AD59"
$PN"AD59"7;
"VSS_AD57"
$PN"AD57"7;
"VSS_AD53"
$PN"AD53"7;
"VSS_AD52"
$PN"AD52"7;
"VSS_AD51"
$PN"AD51"7;
"VSS_AD50"
$PN"AD50"7;
"VSS_AD49"
$PN"AD49"7;
"VSS_AM39"
$PN"AM39"8;
"VSS_AM34"
$PN"AM34"8;
"VSS_AM33"
$PN"AM33"8;
"VSS_AM32"
$PN"AM32"8;
"VSS_AM31"
$PN"AM31"8;
"VSS_AM30"
$PN"AM30"8;
"VSS_AM29"
$PN"AM29"8;
"VSS_AM28"
$PN"AM28"8;
"VSS_AM27"
$PN"AM27"8;
"VSS_AM26"
$PN"AM26"8;
"VSS_AM25"
$PN"AM25"8;
"VSS_AM24"
$PN"AM24"8;
"VSS_AM23"
$PN"AM23"8;
"VSS_AM17"
$PN"AM17"8;
"VSS_AM15"
$PN"AM15"8;
"VSS_AM10"
$PN"AM10"8;
"VSS_AM8"
$PN"AM8"8;
"VSS_AM3"
$PN"AM3"8;
"VSS_AL75"
$PN"AL75"8;
"VSS_AL72"
$PN"AL72"8;
"VSS_AL70"
$PN"AL70"8;
"VSS_AL68"
$PN"AL68"8;
"VSS_AL65"
$PN"AL65"8;
"VSS_AL63"
$PN"AL63"8;
"VSS_AL61"
$PN"AL61"8;
"VSS_AL58"
$PN"AL58"8;
"VSS_AL56"
$PN"AL56"8;
"VSS_AL54"
$PN"AL54"8;
"VSS_AL51"
$PN"AL51"8;
"VSS_AL48"
$PN"AL48"8;
"VSS_AL45"
$PN"AL45"8;
"VSS_AL42"
$PN"AL42"8;
"VSS_AL34"
$PN"AL34"8;
"VSS_AL31"
$PN"AL31"8;
"VSS_AL28"
$PN"AL28"8;
"VSS_AL25"
$PN"AL25"8;
"VSS_AL22"
$PN"AL22"8;
"VSS_AL20"
$PN"AL20"8;
"VSS_AL18"
$PN"AL18"8;
"VSS_AL15"
$PN"AL15"8;
"VSS_AL13"
$PN"AL13"8;
"VSS_AL11"
$PN"AL11"8;
"VSS_AL8"
$PN"AL8"8;
"VSS_AL6"
$PN"AL6"8;
"VSS_AL4"
$PN"AL4"8;
"VSS_AL1"
$PN"AL1"8;
"VSS_AK73"
$PN"AK73"8;
"VSS_AK71"
$PN"AK71"8;
"VSS_AK68"
$PN"AK68"8;
"VSS_AK66"
$PN"AK66"8;
"VSS_AK64"
$PN"AK64"8;
"VSS_AK61"
$PN"AK61"8;
"VSS_AK59"
$PN"AK59"8;
"VSS_AK57"
$PN"AK57"8;
"VSS_AK54"
$PN"AK54"8;
"VSS_AK51"
$PN"AK51"8;
"VSS_AK48"
$PN"AK48"8;
"VSS_AK45"
$PN"AK45"8;
"VSS_AK42"
$PN"AK42"8;
"VSS_AK39"
$PN"AK39"8;
"VSS_AK37"
$PN"AK37"8;
"VSS_AK34"
$PN"AK34"8;
"VSS_AK31"
$PN"AK31"8;
"VSS_AK28"
$PN"AK28"8;
"VSS_AK25"
$PN"AK25"8;
"VSS_AK22"
$PN"AK22"8;
"VSS_AK19"
$PN"AK19"8;
"VSS_AK17"
$PN"AK17"8;
"VSS_AK15"
$PN"AK15"8;
"VSS_AK12"
$PN"AK12"8;
"VSS_AK10"
$PN"AK10"8;
%"GENOA_SP5"
"32","(-2625,3475)","0","pure_quanta","I23";
;
LOCATION"U25"
$SEC"32"
CDS_SEC"32"
PART_TYPE"SMLF"
MATERIAL"IO"
VALUE"SOCKET6096_13568-001"
PART_NUMBER"DGA^6000030"
NEEDS_NO_SIZE"TRUE"
CDS_LMAN_SYM_OUTLINE"-400,3050,400,-3050"
CDS_LIB"pure_quanta";
"VSS_AW61"
$PN"AW61"10;
"VSS_AW58"
$PN"AW58"10;
"VSS_AW56"
$PN"AW56"10;
"VSS_AW53"
$PN"AW53"10;
"VSS_AW51"
$PN"AW51"10;
"VSS_AW49"
$PN"AW49"10;
"VSS_AW28"
$PN"AW28"10;
"VSS_AW26"
$PN"AW26"10;
"VSS_AW24"
$PN"AW24"10;
"VSS_AW22"
$PN"AW22"10;
"VSS_AW20"
$PN"AW20"10;
"VSS_AW18"
$PN"AW18"10;
"VSS_AW15"
$PN"AW15"10;
"VSS_AW13"
$PN"AW13"10;
"VSS_AW11"
$PN"AW11"10;
"VSS_AW8"
$PN"AW8"10;
"VSS_AW6"
$PN"AW6"10;
"VSS_AW4"
$PN"AW4"10;
"VSS_AW1"
$PN"AW1"10;
"VSS_AV73"
$PN"AV73"10;
"VSS_AV68"
$PN"AV68"10;
"VSS_AV66"
$PN"AV66"10;
"VSS_AV61"
$PN"AV61"10;
"VSS_AV59"
$PN"AV59"10;
"VSS_AV54"
$PN"AV54"10;
"VSS_AV52"
$PN"AV52"10;
"VSS_AV50"
$PN"AV50"10;
"VSS_AV48"
$PN"AV48"10;
"VSS_AV46"
$PN"AV46"10;
"VSS_AV44"
$PN"AV44"10;
"VSS_AV42"
$PN"AV42"10;
"VSS_AV40"
$PN"AV40"10;
"VSS_AV37"
$PN"AV37"10;
"VSS_AV35"
$PN"AV35"10;
"VSS_AV33"
$PN"AV33"10;
"VSS_AV31"
$PN"AV31"10;
"VSS_AV29"
$PN"AV29"10;
"VSS_AV27"
$PN"AV27"10;
"VSS_AV25"
$PN"AV25"10;
"VSS_AV23"
$PN"AV23"10;
"VSS_AV17"
$PN"AV17"10;
"VSS_AV15"
$PN"AV15"10;
"VSS_AV10"
$PN"AV10"10;
"VSS_AV8"
$PN"AV8"10;
"VSS_AV3"
$PN"AV3"10;
"VSS_AU75"
$PN"AU75"10;
"VSS_AU73"
$PN"AU73"10;
"VSS_AU72"
$PN"AU72"10;
"VSS_AU70"
$PN"AU70"10;
"VSS_AU68"
$PN"AU68"10;
"VSS_AU65"
$PN"AU65"10;
"VSS_AU63"
$PN"AU63"10;
"VSS_AU61"
$PN"AU61"10;
"VSS_AU58"
$PN"AU58"10;
"VSS_AU56"
$PN"AU56"10;
"VSS_AU53"
$PN"AU53"10;
"VSS_AU51"
$PN"AU51"10;
"VSS_AU49"
$PN"AU49"10;
"VSS_AU47"
$PN"AU47"10;
"VSS_AU45"
$PN"AU45"10;
"VSS_AU43"
$PN"AU43"10;
"VSS_AU41"
$PN"AU41"10;
"VSS_AU36"
$PN"AU36"10;
"VSS_AU34"
$PN"AU34"10;
"VSS_AU32"
$PN"AU32"10;
"VSS_AU30"
$PN"AU30"10;
"VSS_AU28"
$PN"AU28"10;
"VSS_AU26"
$PN"AU26"10;
"VSS_AU24"
$PN"AU24"10;
"VSS_AU22"
$PN"AU22"10;
"VSS_AU20"
$PN"AU20"10;
"VSS_AU18"
$PN"AU18"10;
"VSS_AU15"
$PN"AU15"10;
"VSS_AU13"
$PN"AU13"10;
"VSS_AU11"
$PN"AU11"10;
"VSS_AU8"
$PN"AU8"10;
"VSS_AU6"
$PN"AU6"10;
"VSS_AU4"
$PN"AU4"10;
"VSS_AU3"
$PN"AU3"10;
"VSS_AU1"
$PN"AU1"10;
"VSS_AT73"
$PN"AT73"10;
"VSS_AT72"
$PN"AT72"10;
"VSS_AT71"
$PN"AT71"10;
"VSS_AT70"
$PN"AT70"10;
"VSS_AT68"
$PN"AT68"10;
"VSS_AT67"
$PN"AT67"10;
"VSS_AT66"
$PN"AT66"10;
"VSS_AT64"
$PN"AT64"10;
"VSS_AT63"
$PN"AT63"10;
"VSS_AT61"
$PN"AT61"10;
"VSS_AT60"
$PN"AT60"10;
"VSS_AT59"
$PN"AT59"10;
"VSS_AT57"
$PN"AT57"10;
"VSS_AT56"
$PN"AT56"10;
"VSS_AT54"
$PN"AT54"10;
"VSS_AT52"
$PN"AT52"10;
"VSS_AT50"
$PN"AT50"10;
"VSS_AT48"
$PN"AT48"10;
"VSS_AT46"
$PN"AT46"10;
"VSS_AT44"
$PN"AT44"10;
"VSS_AT42"
$PN"AT42"10;
"VSS_AT40"
$PN"AT40"10;
"VSS_AT37"
$PN"AT37"10;
"VSS_AT35"
$PN"AT35"10;
"VSS_AT33"
$PN"AT33"10;
"VSS_AT31"
$PN"AT31"10;
"VSS_AT29"
$PN"AT29"10;
"VSS_AT27"
$PN"AT27"10;
"VSS_AT25"
$PN"AT25"10;
"VSS_AT23"
$PN"AT23"10;
"VSS_AT20"
$PN"AT20"10;
"VSS_AT19"
$PN"AT19"10;
"VSS_AT17"
$PN"AT17"10;
"VSS_AT16"
$PN"AT16"10;
"VSS_AT15"
$PN"AT15"10;
"VSS_AT13"
$PN"AT13"10;
"VSS_AT12"
$PN"AT12"10;
"VSS_AT10"
$PN"AT10"10;
"VSS_AT9"
$PN"AT9"10;
"VSS_AT8"
$PN"AT8"9;
"VSS_AT6"
$PN"AT6"9;
"VSS_AT5"
$PN"AT5"9;
"VSS_AT4"
$PN"AT4"9;
"VSS_AT3"
$PN"AT3"9;
"VSS_AR75"
$PN"AR75"9;
"VSS_AR71"
$PN"AR71"9;
"VSS_AR70"
$PN"AR70"9;
"VSS_AR68"
$PN"AR68"9;
"VSS_AR67"
$PN"AR67"9;
"VSS_AR64"
$PN"AR64"9;
"VSS_AR63"
$PN"AR63"9;
"VSS_AR61"
$PN"AR61"9;
"VSS_AR60"
$PN"AR60"9;
"VSS_AR57"
$PN"AR57"9;
"VSS_AR56"
$PN"AR56"9;
"VSS_AR53"
$PN"AR53"9;
"VSS_AR51"
$PN"AR51"9;
"VSS_AR49"
$PN"AR49"9;
"VSS_AR47"
$PN"AR47"9;
"VSS_AR45"
$PN"AR45"9;
"VSS_AR43"
$PN"AR43"9;
"VSS_AR41"
$PN"AR41"9;
"VSS_AR36"
$PN"AR36"9;
"VSS_AR34"
$PN"AR34"9;
"VSS_AR32"
$PN"AR32"9;
"VSS_AR30"
$PN"AR30"9;
"VSS_AR28"
$PN"AR28"9;
"VSS_AR26"
$PN"AR26"9;
"VSS_AR24"
$PN"AR24"9;
"VSS_AR22"
$PN"AR22"9;
"VSS_AR20"
$PN"AR20"9;
"VSS_AR19"
$PN"AR19"9;
"VSS_AR16"
$PN"AR16"9;
"VSS_AR15"
$PN"AR15"9;
"VSS_AR13"
$PN"AR13"9;
"VSS_AR12"
$PN"AR12"9;
"VSS_AR9"
$PN"AR9"9;
"VSS_AR8"
$PN"AR8"9;
"VSS_AR6"
$PN"AR6"9;
"VSS_AR5"
$PN"AR5"9;
"VSS_AR1"
$PN"AR1"9;
"VSS_AP73"
$PN"AP73"9;
"VSS_AP71"
$PN"AP71"9;
"VSS_AP68"
$PN"AP68"9;
"VSS_AP66"
$PN"AP66"9;
"VSS_AP64"
$PN"AP64"9;
"VSS_AP61"
$PN"AP61"9;
"VSS_AP59"
$PN"AP59"9;
"VSS_AP57"
$PN"AP57"9;
"VSS_AP54"
$PN"AP54"9;
"VSS_AP51"
$PN"AP51"9;
"VSS_AP48"
$PN"AP48"9;
"VSS_AP45"
$PN"AP45"9;
"VSS_AP42"
$PN"AP42"9;
"VSS_AP39"
$PN"AP39"9;
"VSS_AP37"
$PN"AP37"9;
"VSS_AP34"
$PN"AP34"9;
"VSS_AP31"
$PN"AP31"9;
"VSS_AP28"
$PN"AP28"9;
"VSS_AP25"
$PN"AP25"9;
"VSS_AP22"
$PN"AP22"9;
"VSS_AP19"
$PN"AP19"9;
"VSS_AP17"
$PN"AP17"9;
"VSS_AP15"
$PN"AP15"9;
"VSS_AP12"
$PN"AP12"9;
"VSS_AP10"
$PN"AP10"9;
"VSS_AP8"
$PN"AP8"9;
"VSS_AP5"
$PN"AP5"9;
"VSS_AP3"
$PN"AP3"9;
"VSS_AN75"
$PN"AN75"9;
"VSS_AN72"
$PN"AN72"9;
"VSS_AN70"
$PN"AN70"9;
"VSS_AN68"
$PN"AN68"9;
"VSS_AN65"
$PN"AN65"9;
"VSS_AN63"
$PN"AN63"9;
"VSS_AN61"
$PN"AN61"9;
"VSS_AN58"
$PN"AN58"9;
"VSS_AN56"
$PN"AN56"9;
"VSS_AN54"
$PN"AN54"9;
"VSS_AN51"
$PN"AN51"9;
"VSS_AN48"
$PN"AN48"9;
"VSS_AN45"
$PN"AN45"9;
"VSS_AN42"
$PN"AN42"9;
"VSS_AN41"
$PN"AN41"9;
"VSS_AN40"
$PN"AN40"9;
"VSS_AN36"
$PN"AN36"9;
"VSS_AN35"
$PN"AN35"9;
"VSS_AN34"
$PN"AN34"9;
"VSS_AN31"
$PN"AN31"9;
"VSS_AN28"
$PN"AN28"9;
"VSS_AN25"
$PN"AN25"9;
"VSS_AN22"
$PN"AN22"9;
"VSS_AN18"
$PN"AN18"9;
"VSS_AN15"
$PN"AN15"9;
"VSS_AN13"
$PN"AN13"9;
"VSS_AN11"
$PN"AN11"9;
"VSS_AN8"
$PN"AN8"9;
"VSS_AN6"
$PN"AN6"9;
"VSS_AN4"
$PN"AN4"9;
"VSS_AN1"
$PN"AN1"9;
"VSS_AM73"
$PN"AM73"9;
"VSS_AM68"
$PN"AM68"9;
"VSS_AM66"
$PN"AM66"9;
"VSS_AM61"
$PN"AM61"9;
"VSS_AM59"
$PN"AM59"9;
"VSS_AM53"
$PN"AM53"9;
"VSS_AM52"
$PN"AM52"9;
"VSS_AM51"
$PN"AM51"9;
"VSS_AM50"
$PN"AM50"9;
"VSS_AM49"
$PN"AM49"9;
"VSS_AM48"
$PN"AM48"9;
"VSS_AM47"
$PN"AM47"9;
"VSS_AM46"
$PN"AM46"9;
"VSS_AM45"
$PN"AM45"9;
"VSS_AM44"
$PN"AM44"9;
"VSS_AM43"
$PN"AM43"9;
"VSS_AM42"
$PN"AM42"9;
%"GENOA_SP5"
"33","(-1000,3475)","0","pure_quanta","I24";
;
LOCATION"U25"
$SEC"33"
CDS_SEC"33"
PART_TYPE"SMLF"
MATERIAL"IO"
VALUE"SOCKET6096_13568-001"
PART_NUMBER"DGA^6000030"
NEEDS_NO_SIZE"TRUE"
CDS_LMAN_SYM_OUTLINE"-400,3050,400,-3050"
CDS_LIB"pure_quanta";
"VSS_BL24"
$PN"BL24"12;
"VSS_BL22"
$PN"BL22"12;
"VSS_BL20"
$PN"BL20"12;
"VSS_BL18"
$PN"BL18"12;
"VSS_BL15"
$PN"BL15"12;
"VSS_BL13"
$PN"BL13"12;
"VSS_BL11"
$PN"BL11"12;
"VSS_BL8"
$PN"BL8"12;
"VSS_BL6"
$PN"BL6"12;
"VSS_BL4"
$PN"BL4"12;
"VSS_BL1"
$PN"BL1"12;
"VSS_BK73"
$PN"BK73"12;
"VSS_BK71"
$PN"BK71"12;
"VSS_BK68"
$PN"BK68"12;
"VSS_BK66"
$PN"BK66"12;
"VSS_BK64"
$PN"BK64"12;
"VSS_BK61"
$PN"BK61"12;
"VSS_BK59"
$PN"BK59"12;
"VSS_BK57"
$PN"BK57"12;
"VSS_BK54"
$PN"BK54"12;
"VSS_BK52"
$PN"BK52"12;
"VSS_BK50"
$PN"BK50"12;
"VSS_BK48"
$PN"BK48"12;
"VSS_BK27"
$PN"BK27"12;
"VSS_BK25"
$PN"BK25"12;
"VSS_BK23"
$PN"BK23"12;
"VSS_BK19"
$PN"BK19"12;
"VSS_BK17"
$PN"BK17"12;
"VSS_BK15"
$PN"BK15"12;
"VSS_BK12"
$PN"BK12"12;
"VSS_BK10"
$PN"BK10"12;
"VSS_BK8"
$PN"BK8"12;
"VSS_BK5"
$PN"BK5"12;
"VSS_BK3"
$PN"BK3"12;
"VSS_BJ75"
$PN"BJ75"12;
"VSS_BJ70"
$PN"BJ70"12;
"VSS_BJ68"
$PN"BJ68"12;
"VSS_BJ63"
$PN"BJ63"12;
"VSS_BJ61"
$PN"BJ61"12;
"VSS_BJ56"
$PN"BJ56"12;
"VSS_BJ53"
$PN"BJ53"12;
"VSS_BJ51"
$PN"BJ51"12;
"VSS_BJ49"
$PN"BJ49"12;
"VSS_BJ28"
$PN"BJ28"12;
"VSS_BJ26"
$PN"BJ26"12;
"VSS_BJ24"
$PN"BJ24"12;
"VSS_BJ22"
$PN"BJ22"12;
"VSS_BJ20"
$PN"BJ20"12;
"VSS_BJ15"
$PN"BJ15"12;
"VSS_BJ13"
$PN"BJ13"12;
"VSS_BJ8"
$PN"BJ8"12;
"VSS_BJ6"
$PN"BJ6"12;
"VSS_BJ1"
$PN"BJ1"12;
"VSS_BH73"
$PN"BH73"12;
"VSS_BH71"
$PN"BH71"12;
"VSS_BH68"
$PN"BH68"12;
"VSS_BH66"
$PN"BH66"12;
"VSS_BH64"
$PN"BH64"12;
"VSS_BH61"
$PN"BH61"12;
"VSS_BH59"
$PN"BH59"12;
"VSS_BH57"
$PN"BH57"12;
"VSS_BH54"
$PN"BH54"12;
"VSS_BH52"
$PN"BH52"12;
"VSS_BH50"
$PN"BH50"12;
"VSS_BH49"
$PN"BH49"12;
"VSS_BH28"
$PN"BH28"12;
"VSS_BH26"
$PN"BH26"12;
"VSS_BH24"
$PN"BH24"12;
"VSS_BH22"
$PN"BH22"12;
"VSS_BH19"
$PN"BH19"12;
"VSS_BH17"
$PN"BH17"12;
"VSS_BH15"
$PN"BH15"12;
"VSS_BH12"
$PN"BH12"12;
"VSS_BH10"
$PN"BH10"12;
"VSS_BH8"
$PN"BH8"12;
"VSS_BH5"
$PN"BH5"12;
"VSS_BH3"
$PN"BH3"12;
"VSS_BG75"
$PN"BG75"12;
"VSS_BG72"
$PN"BG72"12;
"VSS_BG70"
$PN"BG70"12;
"VSS_BG68"
$PN"BG68"12;
"VSS_BG65"
$PN"BG65"12;
"VSS_BG63"
$PN"BG63"12;
"VSS_BG61"
$PN"BG61"12;
"VSS_BG58"
$PN"BG58"12;
"VSS_BG56"
$PN"BG56"12;
"VSS_BG53"
$PN"BG53"12;
"VSS_BG51"
$PN"BG51"12;
"VSS_BG49"
$PN"BG49"12;
"VSS_BG27"
$PN"BG27"12;
"VSS_BG25"
$PN"BG25"12;
"VSS_BG23"
$PN"BG23"12;
"VSS_BG20"
$PN"BG20"12;
"VSS_BG18"
$PN"BG18"12;
"VSS_BG15"
$PN"BG15"12;
"VSS_BG13"
$PN"BG13"12;
"VSS_BG11"
$PN"BG11"12;
"VSS_BG8"
$PN"BG8"12;
"VSS_BG6"
$PN"BG6"12;
"VSS_BG4"
$PN"BG4"12;
"VSS_BG1"
$PN"BG1"12;
"VSS_BF73"
$PN"BF73"12;
"VSS_BF68"
$PN"BF68"12;
"VSS_BF66"
$PN"BF66"12;
"VSS_BF61"
$PN"BF61"12;
"VSS_BF59"
$PN"BF59"12;
"VSS_BF54"
$PN"BF54"12;
"VSS_BF52"
$PN"BF52"12;
"VSS_BF50"
$PN"BF50"12;
"VSS_BF49"
$PN"BF49"12;
"VSS_BF28"
$PN"BF28"12;
"VSS_BF26"
$PN"BF26"12;
"VSS_BF24"
$PN"BF24"12;
"VSS_BF22"
$PN"BF22"12;
"VSS_BF19"
$PN"BF19"12;
"VSS_BF17"
$PN"BF17"12;
"VSS_BF15"
$PN"BF15"12;
"VSS_BF12"
$PN"BF12"12;
"VSS_BF10"
$PN"BF10"12;
"VSS_BF8"
$PN"BF8"11;
"VSS_BF5"
$PN"BF5"11;
"VSS_BF3"
$PN"BF3"11;
"VSS_BD73"
$PN"BD73"11;
"VSS_BD71"
$PN"BD71"11;
"VSS_BD68"
$PN"BD68"11;
"VSS_BD66"
$PN"BD66"11;
"VSS_BD64"
$PN"BD64"11;
"VSS_BD61"
$PN"BD61"11;
"VSS_BD59"
$PN"BD59"11;
"VSS_BD57"
$PN"BD57"11;
"VSS_BD53"
$PN"BD53"11;
"VSS_BD51"
$PN"BD51"11;
"VSS_BD49"
$PN"BD49"11;
"VSS_BD27"
$PN"BD27"11;
"VSS_BD25"
$PN"BD25"11;
"VSS_BD23"
$PN"BD23"11;
"VSS_BD17"
$PN"BD17"11;
"VSS_BD15"
$PN"BD15"11;
"VSS_BD10"
$PN"BD10"11;
"VSS_BD8"
$PN"BD8"11;
"VSS_BD3"
$PN"BD3"11;
"VSS_BC75"
$PN"BC75"11;
"VSS_BC72"
$PN"BC72"11;
"VSS_BC70"
$PN"BC70"11;
"VSS_BC68"
$PN"BC68"11;
"VSS_BC65"
$PN"BC65"11;
"VSS_BC63"
$PN"BC63"11;
"VSS_BC61"
$PN"BC61"11;
"VSS_BC58"
$PN"BC58"11;
"VSS_BC56"
$PN"BC56"11;
"VSS_BC53"
$PN"BC53"11;
"VSS_BC51"
$PN"BC51"11;
"VSS_BC50"
$PN"BC50"11;
"VSS_BC49"
$PN"BC49"11;
"VSS_BC28"
$PN"BC28"11;
"VSS_BC26"
$PN"BC26"11;
"VSS_BC24"
$PN"BC24"11;
"VSS_BC22"
$PN"BC22"11;
"VSS_BC20"
$PN"BC20"11;
"VSS_BC18"
$PN"BC18"11;
"VSS_BC15"
$PN"BC15"11;
"VSS_BC13"
$PN"BC13"11;
"VSS_BC11"
$PN"BC11"11;
"VSS_BC8"
$PN"BC8"11;
"VSS_BC6"
$PN"BC6"11;
"VSS_BC4"
$PN"BC4"11;
"VSS_BC1"
$PN"BC1"11;
"VSS_BB73"
$PN"BB73"11;
"VSS_BB71"
$PN"BB71"11;
"VSS_BB68"
$PN"BB68"11;
"VSS_BB66"
$PN"BB66"11;
"VSS_BB64"
$PN"BB64"11;
"VSS_BB61"
$PN"BB61"11;
"VSS_BB59"
$PN"BB59"11;
"VSS_BB57"
$PN"BB57"11;
"VSS_BB54"
$PN"BB54"11;
"VSS_BB52"
$PN"BB52"11;
"VSS_BB50"
$PN"BB50"11;
"VSS_BB48"
$PN"BB48"11;
"VSS_BB27"
$PN"BB27"11;
"VSS_BB25"
$PN"BB25"11;
"VSS_BB23"
$PN"BB23"11;
"VSS_BB19"
$PN"BB19"11;
"VSS_BB17"
$PN"BB17"11;
"VSS_BB15"
$PN"BB15"11;
"VSS_BB12"
$PN"BB12"11;
"VSS_BB10"
$PN"BB10"11;
"VSS_BB8"
$PN"BB8"11;
"VSS_BB5"
$PN"BB5"11;
"VSS_BB3"
$PN"BB3"11;
"VSS_BA75"
$PN"BA75"11;
"VSS_BA70"
$PN"BA70"11;
"VSS_BA68"
$PN"BA68"11;
"VSS_BA63"
$PN"BA63"11;
"VSS_BA61"
$PN"BA61"11;
"VSS_BA56"
$PN"BA56"11;
"VSS_BA53"
$PN"BA53"11;
"VSS_BA51"
$PN"BA51"11;
"VSS_BA49"
$PN"BA49"11;
"VSS_BA28"
$PN"BA28"11;
"VSS_BA26"
$PN"BA26"11;
"VSS_BA24"
$PN"BA24"11;
"VSS_BA22"
$PN"BA22"11;
"VSS_BA20"
$PN"BA20"11;
"VSS_BA15"
$PN"BA15"11;
"VSS_BA13"
$PN"BA13"11;
"VSS_BA8"
$PN"BA8"11;
"VSS_BA6"
$PN"BA6"11;
"VSS_BA1"
$PN"BA1"11;
"VSS_AY73"
$PN"AY73"11;
"VSS_AY71"
$PN"AY71"11;
"VSS_AY68"
$PN"AY68"11;
"VSS_AY66"
$PN"AY66"11;
"VSS_AY64"
$PN"AY64"11;
"VSS_AY61"
$PN"AY61"11;
"VSS_AY59"
$PN"AY59"11;
"VSS_AY57"
$PN"AY57"11;
"VSS_AY54"
$PN"AY54"11;
"VSS_AY52"
$PN"AY52"11;
"VSS_AY50"
$PN"AY50"11;
"VSS_AY48"
$PN"AY48"11;
"VSS_AY27"
$PN"AY27"11;
"VSS_AY25"
$PN"AY25"11;
"VSS_AY23"
$PN"AY23"11;
"VSS_AY19"
$PN"AY19"11;
"VSS_AY17"
$PN"AY17"11;
"VSS_AY15"
$PN"AY15"11;
"VSS_AY12"
$PN"AY12"11;
"VSS_AY10"
$PN"AY10"11;
"VSS_AY8"
$PN"AY8"11;
"VSS_AY5"
$PN"AY5"11;
"VSS_AY3"
$PN"AY3"11;
"VSS_AW75"
$PN"AW75"11;
"VSS_AW72"
$PN"AW72"11;
"VSS_AW70"
$PN"AW70"11;
"VSS_AW68"
$PN"AW68"11;
"VSS_AW65"
$PN"AW65"11;
"VSS_AW63"
$PN"AW63"11;
%"UNIVERSAL_GND"
"1","(-9275,350)","0","pure_quanta_power","I39";
;
CDS_LIB"pure_quanta_power"
HDL_POWER"GND";
"A"1;
%"UNIVERSAL_GND"
"1","(-7750,375)","0","pure_quanta_power","I40";
;
CDS_LIB"pure_quanta_power"
HDL_POWER"GND";
"A"3;
%"UNIVERSAL_GND"
"1","(-6275,400)","0","pure_quanta_power","I41";
;
CDS_LIB"pure_quanta_power"
HDL_POWER"GND";
"A"5;
%"UNIVERSAL_GND"
"1","(-3275,425)","0","pure_quanta_power","I43";
;
CDS_LIB"pure_quanta_power"
HDL_POWER"GND";
"A"9;
%"UNIVERSAL_GND"
"1","(-1650,450)","0","pure_quanta_power","I44";
;
CDS_LIB"pure_quanta_power"
HDL_POWER"GND";
"A"11;
%"UNIVERSAL_GND"
"1","(-7925,375)","0","pure_quanta_power","I45";
;
CDS_LIB"pure_quanta_power"
HDL_POWER"GND";
"A"2;
%"UNIVERSAL_GND"
"1","(-6400,400)","0","pure_quanta_power","I46";
;
CDS_LIB"pure_quanta_power"
HDL_POWER"GND";
"A"4;
%"UNIVERSAL_GND"
"1","(-4925,475)","0","pure_quanta_power","I47";
;
CDS_LIB"pure_quanta_power"
HDL_POWER"GND";
"A"6;
%"UNIVERSAL_GND"
"1","(-3425,500)","0","pure_quanta_power","I48";
;
CDS_LIB"pure_quanta_power"
HDL_POWER"GND";
"A"8;
%"UNIVERSAL_GND"
"1","(-1950,450)","0","pure_quanta_power","I49";
;
CDS_LIB"pure_quanta_power"
HDL_POWER"GND";
"A"10;
%"UNIVERSAL_GND"
"1","(-325,450)","0","pure_quanta_power","I50";
;
CDS_LIB"pure_quanta_power"
HDL_POWER"GND";
"A"12;
%"UNIVERSAL_GND"
"1","(-4775,475)","0","pure_quanta_power","I51";
;
CDS_LIB"pure_quanta_power"
HDL_POWER"GND";
"A"7;
END.
